#ISCELL
  mstr_misc dns *
  *
#ISCELL
  mstr_symbols cad_note *
  *
#ISCELL
  mstr_symbols design_note *
  *
#ISCELL
  mstr_symbols intel_corp_bpage *
  *
#CELL
  mstr_vreg tps2061 *
  page176_i100
#ISCELL
  mstr_symbols p5v *
  page176_i101
#ISCELL
  mstr_symbols gnd *
  page176_i102
#ISCELL
  mstr_standard offpage *
  page176_i103
#ISCELL
  mstr_standard offpage *
  page176_i104
#CELL
  mstr_discrete res *
  page176_i105
#CELL
  dev_discrete cap_a *
  page176_i108
#ISCELL
  mstr_symbols gnd *
  page176_i109
#ISCELL
  mstr_symbols p3v3_stby *
  page176_i110
#CELL
  mstr_discrete res *
  page176_i111
#ISCELL
  mstr_symbols gnd *
  page176_i112
#CELL
  mstr_discrete capp *
  page176_i113
#ISCELL
  mstr_symbols gnd *
  page176_i114
#ISCELL
  mstr_standard offpage *
  page176_i119
#ISCELL
  mstr_standard offpage *
  page176_i123
#ISCELL
  mstr_symbols gnd *
  page176_i125
#ISCELL
  mstr_symbols p3v3_stby *
  page176_i126
#ISCELL
  mstr_standard offpage *
  page176_i127
#ISCELL
  mstr_standard offpage *
  page176_i130
#CELL
  mstr_discrete res *
  page176_i132
#CELL
  mstr_discrete res *
  page176_i133
#ISCELL
  mstr_symbols p5v_stby *
  page176_i134
#ISCELL
  mstr_standard offpage *
  page176_i135
#ISCELL
  mstr_standard offpage *
  page176_i136
#CELL
  mstr_discrete res *
  page176_i137
#CELL
  mstr_discrete res *
  page176_i138
#CELL
  dev_discrete cap_a *
  page176_i139
#ISCELL
  mstr_symbols p3v3_stby *
  page176_i140
#CELL
  mstr_discrete res *
  page176_i142
#CELL
  mstr_discrete res *
  page176_i143
#ISCELL
  mstr_standard offpage *
  page176_i144
#ISCELL
  mstr_standard offpage *
  page176_i145
#CELL
  mstr_ttl ttl1g126_a *
  page176_i146
#CELL
  mstr_discrete res *
  page176_i147
#CELL
  mstr_ttl ttl1g126_a *
  page176_i148
#ISCELL
  mstr_standard offpage *
  page176_i149
#ISCELL
  mstr_symbols gnd *
  page176_i151
#ISCELL
  mstr_standard offpage *
  page176_i155
#CELL
  mstr_discrete res *
  page176_i156
#CELL
  mstr_ttl ttl1g126_a *
  page176_i157
#CELL
  mstr_discrete res *
  page176_i158
#ISCELL
  mstr_symbols p3v3_stby *
  page176_i159
#CELL
  mstr_discrete res *
  page176_i16
#CELL
  mstr_discrete res *
  page176_i160
#CELL
  mstr_discrete res *
  page176_i161
#CELL
  mstr_digital pca9617 *
  page176_i162
#CELL
  dev_discrete cap_a *
  page176_i163
#ISCELL
  mstr_symbols gnd *
  page176_i164
#CELL
  dev_discrete cap_a *
  page176_i166
#ISCELL
  mstr_symbols gnd *
  page176_i167
#ISCELL
  mstr_symbols p3v3_stby *
  page176_i168
#ISCELL
  mstr_symbols p3v3_stby *
  page176_i169
#ISCELL
  mstr_symbols p3v3_stby *
  page176_i170
#ISCELL
  mstr_symbols p3v3_stby *
  page176_i171
#CELL
  mstr_discrete res *
  page176_i172
#CELL
  mstr_discrete res *
  page176_i173
#ISCELL
  mstr_symbols p3v3_stby *
  page176_i174
#CELL
  mstr_discrete res *
  page176_i175
#CELL
  mstr_discrete res *
  page176_i176
#CELL
  mstr_discrete res *
  page176_i178
#ISCELL
  mstr_symbols p3v3_stby *
  page176_i179
#CELL
  mstr_discrete choke_4pin *
  page176_i181
#CELL
  mstr_analog nc7sb3157 *
  page176_i182
#ISCELL
  mstr_symbols gnd *
  page176_i183
#CELL
  mstr_discrete res *
  page176_i31
#ISCELL
  mstr_standard offpage *
  page176_i46
#ISCELL
  mstr_standard offpage *
  page176_i47
#CELL
  mstr_conn conn9_h51826001 *
  page176_i69
#ISCELL
  mstr_symbols gnd *
  page176_i70
#ISCELL
  mstr_symbols gnd *
  page176_i71
#ISCELL
  mstr_standard offpage *
  page176_i75
#CELL
  mstr_discrete diodeac_dual_array *
  page176_i98
#ISCELL
  mstr_symbols gnd *
  page176_i99
